# S9S_MB_2U (Grand Teton) — schematic netlist excerpt (pin names and nets, part order shuffled) for the footprints in the layout excerpt that follows; sources: Cadence DE-HDL packaged netlist, KiCad conversion of 03242023_DA0F0TMBIJ0_F0T_Motherboard_J_brd_V01_OCP.brd

R578  Q_RES  33.2 1% CHIP  pkg 0402LF  page 241 : A = SMB_HOST_3V3AUX_SDA_R4 ; B = SMB_HOST_3V3AUX_SDA_R
L20  Q_INDUCTOR  FCM2012KF-601T/0.5A IND  pkg SMLF  page 211 : \1\ = P3V3 ; \2\ = P3V3_9ZXL045_VDD
PC405_P1_1  Q_CAP  22UF 16V 20% X6S  pkg C0805  page 289 : A = SW_P12V_PVCCFA_EHV_FIVRA_CPU1_R ; B = GND

(kicad_pcb
	(version 20260206)
	(generator "pcbnew")
	(generator_version "10.0")
	(general
		(thickness 1.6)
		(legacy_teardrops no)
	)
	(paper "A4")
	(title_block
		(title "03242023_DA0F0TMBIJ0_F0T_Motherboard_J_brd_V01_OCP.brd")
		(comment 1 "Grand Teton / footprints 5117-5119 of 6105")
	)
	(layers
		(0 "F.Cu" signal "TOP")
		(4 "In1.Cu" signal "GND")
		(6 "In2.Cu" signal "IN1")
		(8 "In3.Cu" signal "GND1")
		(10 "In4.Cu" signal "IN2")
		(12 "In5.Cu" signal "GND2")
		(14 "In6.Cu" signal "IN3")
		(16 "In7.Cu" signal "GND3")
		(18 "In8.Cu" signal "VCC")
		(20 "In9.Cu" signal "VCC1")
		(22 "In10.Cu" signal "GND4")
		(24 "In11.Cu" signal "IN4")
		(26 "In12.Cu" signal "GND5")
		(28 "In13.Cu" signal "IN5")
		(30 "In14.Cu" signal "GND6")
		(32 "In15.Cu" signal "IN6")
		(34 "In16.Cu" signal "GND7")
		(2 "B.Cu" signal "BOTTOM")
		(9 "F.Adhes" user "F.Adhesive")
		(11 "B.Adhes" user "B.Adhesive")
		(13 "F.Paste" user "Package Geometry/Pastemask Top")
		(15 "B.Paste" user "Package Geometry/Pastemask Bottom")
		(5 "F.SilkS" user "Ref Des/Silkscreen Top")
		(7 "B.SilkS" user "Ref Des/Silkscreen Bottom")
		(1 "F.Mask" user "Board Geometry/Soldermask Top")
		(3 "B.Mask" user "Board Geometry/Soldermask Bottom")
		(17 "Dwgs.User" user "User.Drawings")
		(19 "Cmts.User" user "User.Comments")
		(21 "Eco1.User" user "User.Eco1")
		(23 "Eco2.User" user "User.Eco2")
		(25 "Edge.Cuts" user "Board Geometry/Outline")
		(27 "Margin" user)
		(31 "F.CrtYd" user "Package Geometry/Place Bound Top")
		(29 "B.CrtYd" user "Package Geometry/Place Bound Bottom")
		(35 "F.Fab" user "Ref Des/Assembly Top")
		(33 "B.Fab" user "Ref Des/Assembly Bottom")
	)
	(footprint ""
		(layer "B.Cu")
		(at 238.161322 -130.3909 -90)
		(property "Reference" "R578"
			(at 0 0 90)
			(layer "B.SilkS")
			(hide yes)
			(effects
				(font
					(size 1.27 1.27)
				)
				(justify mirror)
			)
		)
		(property "Value" ""
			(at 0 0 90)
			(layer "B.Fab")
			(effects
				(font
					(size 1.27 1.27)
				)
				(justify mirror)
			)
		)
		(duplicate_pad_numbers_are_jumpers no)
		(fp_line
			(start -0.7874 0.4064)
			(end 0.7874 0.4064)
			(stroke
				(width 0.1524)
				(type default)
			)
			(layer "B.SilkS")
		)
		(fp_line
			(start 0.7874 0.4064)
			(end 0.7874 -0.4064)
			(stroke
				(width 0.1524)
				(type default)
			)
			(layer "B.SilkS")
		)
		(fp_line
			(start -0.7874 -0.4064)
			(end -0.7874 0.4064)
			(stroke
				(width 0.1524)
				(type default)
			)
			(layer "B.SilkS")
		)
		(fp_line
			(start 0.7874 -0.4064)
			(end -0.7874 -0.4064)
			(stroke
				(width 0.1524)
				(type default)
			)
			(layer "B.SilkS")
		)
		(fp_line
			(start -0.67945 0.3048)
			(end -0.120396 0.3048)
			(stroke
				(width 0.1)
				(type default)
			)
			(layer "B.Fab")
		)
		(fp_line
			(start -0.120396 0.3048)
			(end -0.120396 0.2794)
			(stroke
				(width 0.1)
				(type default)
			)
			(layer "B.Fab")
		)
		(fp_line
			(start 0.12065 0.3048)
			(end 0.67945 0.3048)
			(stroke
				(width 0.1)
				(type default)
			)
			(layer "B.Fab")
		)
		(fp_line
			(start 0.67945 0.3048)
			(end 0.67945 -0.305054)
			(stroke
				(width 0.1)
				(type default)
			)
			(layer "B.Fab")
		)
		(fp_line
			(start -0.120396 0.2794)
			(end 0.12065 0.2794)
			(stroke
				(width 0.1)
				(type default)
			)
			(layer "B.Fab")
		)
		(fp_line
			(start 0.12065 0.2794)
			(end 0.12065 0.3048)
			(stroke
				(width 0.1)
				(type default)
			)
			(layer "B.Fab")
		)
		(fp_line
			(start -0.12065 -0.2794)
			(end -0.12065 -0.3048)
			(stroke
				(width 0.1)
				(type default)
			)
			(layer "B.Fab")
		)
		(fp_line
			(start 0.12065 -0.2794)
			(end -0.12065 -0.2794)
			(stroke
				(width 0.1)
				(type default)
			)
			(layer "B.Fab")
		)
		(fp_line
			(start -0.67945 -0.3048)
			(end -0.67945 0.3048)
			(stroke
				(width 0.1)
				(type default)
			)
			(layer "B.Fab")
		)
		(fp_line
			(start -0.12065 -0.3048)
			(end -0.67945 -0.3048)
			(stroke
				(width 0.1)
				(type default)
			)
			(layer "B.Fab")
		)
		(fp_line
			(start 0.12065 -0.305054)
			(end 0.12065 -0.2794)
			(stroke
				(width 0.1)
				(type default)
			)
			(layer "B.Fab")
		)
		(fp_line
			(start 0.67945 -0.305054)
			(end 0.12065 -0.305054)
			(stroke
				(width 0.1)
				(type default)
			)
			(layer "B.Fab")
		)
		(pad "1" smd circle
			(at 0.40005 0 90)
			(size 0 0)
			(layers "B.Cu" "B.Mask" "B.Paste")
			(net "SMB_HOST_3V3AUX_SDA_R4")
		)
		(pad "2" smd circle
			(at -0.40005 0 90)
			(size 0 0)
			(layers "B.Cu" "B.Mask" "B.Paste")
			(net "SMB_HOST_3V3AUX_SDA_R")
		)
	)
	(footprint ""
		(layer "B.Cu")
		(at 175.281082 -353.726242 90)
		(property "Reference" "PC405_P1_1"
			(at 0 0 90)
			(layer "B.SilkS")
			(hide yes)
			(effects
				(font
					(size 1.27 1.27)
				)
				(justify mirror)
			)
		)
		(property "Value" ""
			(at 0 0 90)
			(layer "B.Fab")
			(effects
				(font
					(size 1.27 1.27)
				)
				(justify mirror)
			)
		)
		(duplicate_pad_numbers_are_jumpers no)
		(fp_line
			(start 1.524 -0.762)
			(end -1.524 -0.762)
			(stroke
				(width 0.1524)
				(type default)
			)
			(layer "B.SilkS")
		)
		(fp_line
			(start -1.524 -0.762)
			(end -1.524 0.762)
			(stroke
				(width 0.1524)
				(type default)
			)
			(layer "B.SilkS")
		)
		(fp_line
			(start 1.524 0.762)
			(end 1.524 -0.762)
			(stroke
				(width 0.1524)
				(type default)
			)
			(layer "B.SilkS")
		)
		(fp_line
			(start -1.524 0.762)
			(end 1.524 0.762)
			(stroke
				(width 0.1524)
				(type default)
			)
			(layer "B.SilkS")
		)
		(fp_line
			(start 1.1049 -0.724916)
			(end 1.1049 0.724916)
			(stroke
				(width 0.1)
				(type default)
			)
			(layer "B.Fab")
		)
		(fp_line
			(start -1.1049 -0.724916)
			(end 1.1049 -0.724916)
			(stroke
				(width 0.1)
				(type default)
			)
			(layer "B.Fab")
		)
		(fp_line
			(start 1.1049 0.724916)
			(end -1.1049 0.724916)
			(stroke
				(width 0.1)
				(type default)
			)
			(layer "B.Fab")
		)
		(fp_line
			(start -1.1049 0.724916)
			(end -1.1049 -0.724916)
			(stroke
				(width 0.1)
				(type default)
			)
			(layer "B.Fab")
		)
		(pad "1" smd rect
			(at 0.889 0 90)
			(size 1.016 1.27)
			(layers "B.Cu" "B.Mask" "B.Paste")
			(net "SW_P12V_PVCCFA_EHV_FIVRA_CPU1_R")
		)
		(pad "2" smd rect
			(at -0.889 0 90)
			(size 1.016 1.27)
			(layers "B.Cu" "B.Mask" "B.Paste")
			(net "GND")
		)
	)
	(footprint ""
		(layer "B.Cu")
		(at 105.13314 -415.323528 180)
		(property "Reference" "L20"
			(at 0 0 0)
			(layer "B.SilkS")
			(hide yes)
			(effects
				(font
					(size 1.27 1.27)
				)
				(justify mirror)
			)
		)
		(property "Value" ""
			(at 0 0 0)
			(layer "B.Fab")
			(effects
				(font
					(size 1.27 1.27)
				)
				(justify mirror)
			)
		)
		(duplicate_pad_numbers_are_jumpers no)
		(fp_line
			(start 1.63576 -0.8128)
			(end 1.63576 0.8128)
			(stroke
				(width 0.1524)
				(type default)
			)
			(layer "B.SilkS")
		)
		(fp_line
			(start 1.63576 -0.8128)
			(end -1.63576 -0.8128)
			(stroke
				(width 0.1524)
				(type default)
			)
			(layer "B.SilkS")
		)
		(fp_line
			(start -1.63576 0.8128)
			(end 1.63576 0.8128)
			(stroke
				(width 0.1524)
				(type default)
			)
			(layer "B.SilkS")
		)
		(fp_line
			(start -1.63576 -0.8128)
			(end -1.63576 0.8128)
			(stroke
				(width 0.1524)
				(type default)
			)
			(layer "B.SilkS")
		)
		(fp_line
			(start 1.56083 0.7366)
			(end 1.524 0.7366)
			(stroke
				(width 0.1)
				(type default)
			)
			(layer "B.Fab")
		)
		(fp_line
			(start 1.56083 -0.738632)
			(end 1.56083 0.7366)
			(stroke
				(width 0.1)
				(type default)
			)
			(layer "B.Fab")
		)
		(fp_line
			(start 1.524 0.7366)
			(end -1.524 0.7366)
			(stroke
				(width 0.1)
				(type default)
			)
			(layer "B.Fab")
		)
		(fp_line
			(start -1.524 0.7366)
			(end -1.560576 0.7366)
			(stroke
				(width 0.1)
				(type default)
			)
			(layer "B.Fab")
		)
		(fp_line
			(start -1.560576 0.7366)
			(end -1.560576 -0.738632)
			(stroke
				(width 0.1)
				(type default)
			)
			(layer "B.Fab")
		)
		(fp_line
			(start -1.560576 -0.738632)
			(end 1.56083 -0.738632)
			(stroke
				(width 0.1)
				(type default)
			)
			(layer "B.Fab")
		)
		(pad "1" smd rect
			(at 0.94996 0 180)
			(size 1.1176 1.3716)
			(layers "B.Cu" "B.Mask" "B.Paste")
			(net "P3V3")
		)
		(pad "2" smd rect
			(at -0.94996 0 180)
			(size 1.1176 1.3716)
			(layers "B.Cu" "B.Mask" "B.Paste")
			(net "P3V3_9ZXL045_VDD")
		)
	)
)
